(kicad_pcb
	(version 20260206)
	(generator "pcbnew")
	(generator_version "10.0")
	(general
		(thickness 1.6)
		(legacy_teardrops no)
	)
	(paper "A4")
	(title_block
		(title "03242023_DA0F0TMBIJ0_F0T_Motherboard_J_brd_V01_OCP.brd")
		(comment 1 "Grand Teton / footprint 3039 of 6105 (U2), pads 4001-4107 of 4677")
	)
	(layers
		(0 "F.Cu" signal "TOP")
		(4 "In1.Cu" signal "GND")
		(6 "In2.Cu" signal "IN1")
		(8 "In3.Cu" signal "GND1")
		(10 "In4.Cu" signal "IN2")
		(12 "In5.Cu" signal "GND2")
		(14 "In6.Cu" signal "IN3")
		(16 "In7.Cu" signal "GND3")
		(18 "In8.Cu" signal "VCC")
		(20 "In9.Cu" signal "VCC1")
		(22 "In10.Cu" signal "GND4")
		(24 "In11.Cu" signal "IN4")
		(26 "In12.Cu" signal "GND5")
		(28 "In13.Cu" signal "IN5")
		(30 "In14.Cu" signal "GND6")
		(32 "In15.Cu" signal "IN6")
		(34 "In16.Cu" signal "GND7")
		(2 "B.Cu" signal "BOTTOM")
		(9 "F.Adhes" user "F.Adhesive")
		(11 "B.Adhes" user "B.Adhesive")
		(13 "F.Paste" user "Package Geometry/Pastemask Top")
		(15 "B.Paste" user "Package Geometry/Pastemask Bottom")
		(5 "F.SilkS" user "Ref Des/Silkscreen Top")
		(7 "B.SilkS" user "Ref Des/Silkscreen Bottom")
		(1 "F.Mask" user "Board Geometry/Soldermask Top")
		(3 "B.Mask" user "Board Geometry/Soldermask Bottom")
		(17 "Dwgs.User" user "User.Drawings")
		(19 "Cmts.User" user "User.Comments")
		(21 "Eco1.User" user "User.Eco1")
		(23 "Eco2.User" user "User.Eco2")
		(25 "Edge.Cuts" user "Board Geometry/Outline")
		(27 "Margin" user)
		(31 "F.CrtYd" user "Package Geometry/Place Bound Top")
		(29 "B.CrtYd" user "Package Geometry/Place Bound Bottom")
		(35 "F.Fab" user "Ref Des/Assembly Top")
		(33 "B.Fab" user "Ref Des/Assembly Bottom")
	)
	(footprint ""
		(layer "F.Cu")
		(at 359.870248 -251.76988 90)
		(property "Reference" "U2"
			(at -74.416158 -44.488608 0)
			(unlocked yes)
			(layer "F.SilkS")
			(effects
				(font
					(size 1.6002 1.1938)
					(thickness 0.1524)
				)
				(justify left)
			)
		)
		(property "Value" ""
			(at 0 0 90)
			(layer "F.Fab")
			(effects
				(font
					(size 1.27 1.27)
				)
			)
		)
		(duplicate_pad_numbers_are_jumpers no)
		(pad "ET38" smd oval
			(at -7.311136 26.964132 270)
			(size 0.381 0.4826)
			(drill
				(offset 0 -0.0508)
			)
			(layers "F.Cu" "F.Mask" "F.Paste")
			(net "GND")
		)
		(pad "ET40" smd oval
			(at -5.68325 26.964132 270)
			(size 0.381 0.4826)
			(drill
				(offset 0 -0.0508)
			)
			(layers "F.Cu" "F.Mask" "F.Paste")
			(net "M_E_CPU0_SB_CS_N<1>")
		)
		(pad "ET42" smd oval
			(at -4.055618 26.964132 270)
			(size 0.381 0.4826)
			(drill
				(offset 0 -0.0508)
			)
			(layers "F.Cu" "F.Mask" "F.Paste")
			(net "M_E_CPU0_SB_CA<5>")
		)
		(pad "ET49" smd oval
			(at 3.241802 27.074114 270)
			(size 0.381 0.4826)
			(drill
				(offset 0 -0.0508)
			)
			(layers "F.Cu" "F.Mask" "F.Paste")
			(net "M_E_CPU0_SA_CA<1>")
		)
		(pad "ET51" smd oval
			(at 4.869434 27.074114 270)
			(size 0.381 0.4826)
			(drill
				(offset 0 -0.0508)
			)
			(layers "F.Cu" "F.Mask" "F.Paste")
			(net "M_E_CPU0_SA_CS_N<1>")
		)
		(pad "ET53" smd oval
			(at 6.49732 27.074114 270)
			(size 0.381 0.4826)
			(drill
				(offset 0 -0.0508)
			)
			(layers "F.Cu" "F.Mask" "F.Paste")
			(net "GND")
		)
		(pad "ET55" smd oval
			(at 8.124952 27.074114 270)
			(size 0.381 0.4826)
			(drill
				(offset 0 -0.0508)
			)
			(layers "F.Cu" "F.Mask" "F.Paste")
			(net "M_E_CPU0_SA_DQS_DN<9>")
		)
		(pad "ET57" smd oval
			(at 9.752838 27.074114 270)
			(size 0.381 0.4826)
			(drill
				(offset 0 -0.0508)
			)
			(layers "F.Cu" "F.Mask" "F.Paste")
			(net "GND")
		)
		(pad "ET59" smd oval
			(at 11.380724 27.074114 270)
			(size 0.381 0.4826)
			(drill
				(offset 0 -0.0508)
			)
			(layers "F.Cu" "F.Mask" "F.Paste")
			(net "GND")
		)
		(pad "ET61" smd oval
			(at 13.008356 27.074114 270)
			(size 0.381 0.4826)
			(drill
				(offset 0 -0.0508)
			)
			(layers "F.Cu" "F.Mask" "F.Paste")
			(net "M_E_CPU0_SA_DQS_DN<8>")
		)
		(pad "F4" smd oval
			(at -34.98342 -24.724868 135)
			(size 0.381 0.4826)
			(drill
				(offset 0 -0.0508)
			)
			(layers "F.Cu" "F.Mask" "F.Paste")
			(net "GND")
		)
		(pad "F6" smd oval
			(at -33.355534 -24.724868 135)
			(size 0.381 0.4826)
			(drill
				(offset 0 -0.0508)
			)
			(layers "F.Cu" "F.Mask" "F.Paste")
			(net "GND")
		)
		(pad "F8" smd circle
			(at -31.727902 -24.724868 270)
			(size 0.4318 0.4318)
			(layers "F.Cu" "F.Mask" "F.Paste")
			(net "M_A_CPU0_SB_DQ<30>")
		)
		(pad "F10" smd circle
			(at -30.100016 -24.724868 270)
			(size 0.4318 0.4318)
			(layers "F.Cu" "F.Mask" "F.Paste")
			(net "M_A_CPU0_SB_DQ<27>")
		)
		(pad "F12" smd circle
			(at -28.472384 -24.724868 270)
			(size 0.4318 0.4318)
			(layers "F.Cu" "F.Mask" "F.Paste")
			(net "GND")
		)
		(pad "F14" smd circle
			(at -26.844498 -24.724868 270)
			(size 0.4318 0.4318)
			(layers "F.Cu" "F.Mask" "F.Paste")
			(net "M_B_CPU0_SB_DQ<31>")
		)
		(pad "F16" smd circle
			(at -25.216612 -24.724868 270)
			(size 0.4318 0.4318)
			(layers "F.Cu" "F.Mask" "F.Paste")
			(net "M_B_CPU0_SB_DQ<27>")
		)
		(pad "F18" smd circle
			(at -23.58898 -24.724868 270)
			(size 0.4318 0.4318)
			(layers "F.Cu" "F.Mask" "F.Paste")
			(net "GND")
		)
		(pad "F20" smd circle
			(at -21.961094 -24.724868 270)
			(size 0.4318 0.4318)
			(layers "F.Cu" "F.Mask" "F.Paste")
			(net "M_A_CPU0_SB_DQ<22>")
		)
		(pad "F22" smd circle
			(at -20.333462 -24.724868 270)
			(size 0.4318 0.4318)
			(layers "F.Cu" "F.Mask" "F.Paste")
			(net "M_A_CPU0_SB_DQ<19>")
		)
		(pad "F24" smd circle
			(at -18.705576 -24.724868 270)
			(size 0.4318 0.4318)
			(layers "F.Cu" "F.Mask" "F.Paste")
			(net "GND")
		)
		(pad "F26" smd circle
			(at -17.07769 -24.724868 270)
			(size 0.4318 0.4318)
			(layers "F.Cu" "F.Mask" "F.Paste")
			(net "M_A_CPU0_SB_DQ<14>")
		)
		(pad "F28" smd circle
			(at -15.450058 -24.724868 270)
			(size 0.4318 0.4318)
			(layers "F.Cu" "F.Mask" "F.Paste")
			(net "M_A_CPU0_SB_DQ<11>")
		)
		(pad "F30" smd circle
			(at -13.822426 -24.724868 270)
			(size 0.4318 0.4318)
			(layers "F.Cu" "F.Mask" "F.Paste")
			(net "GND")
		)
		(pad "F32" smd circle
			(at -12.19454 -24.724868 270)
			(size 0.4318 0.4318)
			(layers "F.Cu" "F.Mask" "F.Paste")
			(net "M_A_CPU0_SB_CB<2>")
		)
		(pad "F34" smd circle
			(at -10.566654 -24.724868 270)
			(size 0.4318 0.4318)
			(layers "F.Cu" "F.Mask" "F.Paste")
			(net "M_A_CPU0_SB_CB<7>")
		)
		(pad "F36" smd circle
			(at -8.939022 -24.724868 270)
			(size 0.4318 0.4318)
			(layers "F.Cu" "F.Mask" "F.Paste")
			(net "GND")
		)
		(pad "F38" smd circle
			(at -7.311136 -24.724868 270)
			(size 0.4318 0.4318)
			(layers "F.Cu" "F.Mask" "F.Paste")
			(net "M_A_CPU0_SB_CS_N<2>")
		)
		(pad "F40" smd circle
			(at -5.68325 -24.724868 270)
			(size 0.4318 0.4318)
			(layers "F.Cu" "F.Mask" "F.Paste")
			(net "M_A_CPU0_SB_CA<5>")
		)
		(pad "F42" smd circle
			(at -4.055618 -24.724868 270)
			(size 0.4318 0.4318)
			(layers "F.Cu" "F.Mask" "F.Paste")
			(net "GND")
		)
		(pad "F44" smd circle
			(at -2.427732 -24.724868 270)
			(size 0.4318 0.4318)
			(layers "F.Cu" "F.Mask" "F.Paste")
			(net "M_A_CPU0_SB_CA<1>")
		)
		(pad "F47" smd circle
			(at 1.613916 -24.614886 270)
			(size 0.4318 0.4318)
			(layers "F.Cu" "F.Mask" "F.Paste")
			(net "PWRGD_DRAMPWRGD_CPU0_CD_LVC1_R")
		)
		(pad "F49" smd circle
			(at 3.241802 -24.614886 270)
			(size 0.4318 0.4318)
			(layers "F.Cu" "F.Mask" "F.Paste")
			(net "GND")
		)
		(pad "F51" smd circle
			(at 4.869434 -24.614886 270)
			(size 0.4318 0.4318)
			(layers "F.Cu" "F.Mask" "F.Paste")
			(net "M_A_CPU0_SA_CA<3>")
		)
		(pad "F53" smd circle
			(at 6.49732 -24.614886 270)
			(size 0.4318 0.4318)
			(layers "F.Cu" "F.Mask" "F.Paste")
			(net "M_A_CPU0_SA_CS_N<3>")
		)
		(pad "F55" smd circle
			(at 8.124952 -24.614886 270)
			(size 0.4318 0.4318)
			(layers "F.Cu" "F.Mask" "F.Paste")
			(net "GND")
		)
		(pad "F57" smd circle
			(at 9.752838 -24.614886 270)
			(size 0.4318 0.4318)
			(layers "F.Cu" "F.Mask" "F.Paste")
			(net "M_A_CPU0_SA_CB<6>")
		)
		(pad "F59" smd circle
			(at 11.380724 -24.614886 270)
			(size 0.4318 0.4318)
			(layers "F.Cu" "F.Mask" "F.Paste")
			(net "M_A_CPU0_SA_CB<3>")
		)
		(pad "F61" smd circle
			(at 13.008356 -24.614886 270)
			(size 0.4318 0.4318)
			(layers "F.Cu" "F.Mask" "F.Paste")
			(net "GND")
		)
		(pad "F63" smd circle
			(at 14.635988 -24.614886 270)
			(size 0.4318 0.4318)
			(layers "F.Cu" "F.Mask" "F.Paste")
			(net "M_A_CPU0_SA_DQ<30>")
		)
		(pad "F65" smd circle
			(at 16.263874 -24.614886 270)
			(size 0.4318 0.4318)
			(layers "F.Cu" "F.Mask" "F.Paste")
			(net "M_A_CPU0_SA_DQ<27>")
		)
		(pad "F67" smd circle
			(at 17.89176 -24.614886 270)
			(size 0.4318 0.4318)
			(layers "F.Cu" "F.Mask" "F.Paste")
			(net "GND")
		)
		(pad "F69" smd circle
			(at 19.519392 -24.614886 270)
			(size 0.4318 0.4318)
			(layers "F.Cu" "F.Mask" "F.Paste")
			(net "M_A_CPU0_SA_DQ<22>")
		)
		(pad "F71" smd circle
			(at 21.147278 -24.614886 270)
			(size 0.4318 0.4318)
			(layers "F.Cu" "F.Mask" "F.Paste")
			(net "M_A_CPU0_SA_DQ<19>")
		)
		(pad "F73" smd circle
			(at 22.77491 -24.614886 270)
			(size 0.4318 0.4318)
			(layers "F.Cu" "F.Mask" "F.Paste")
			(net "GND")
		)
		(pad "F75" smd circle
			(at 24.402796 -24.614886 270)
			(size 0.4318 0.4318)
			(layers "F.Cu" "F.Mask" "F.Paste")
			(net "M_A_CPU0_SA_DQ<7>")
		)
		(pad "F77" smd circle
			(at 26.030682 -24.614886 270)
			(size 0.4318 0.4318)
			(layers "F.Cu" "F.Mask" "F.Paste")
			(net "M_A_CPU0_SA_DQS_DP<5>")
		)
		(pad "F79" smd circle
			(at 27.658314 -24.614886 270)
			(size 0.4318 0.4318)
			(layers "F.Cu" "F.Mask" "F.Paste")
			(net "GND")
		)
		(pad "F81" smd circle
			(at 29.2862 -24.614886 270)
			(size 0.4318 0.4318)
			(layers "F.Cu" "F.Mask" "F.Paste")
			(net "UPI_CPU1_CPU0_P2P2_DP<22>")
		)
		(pad "F83" smd circle
			(at 30.914086 -24.614886 270)
			(size 0.4318 0.4318)
			(layers "F.Cu" "F.Mask" "F.Paste")
			(net "GND")
		)
		(pad "F85" smd circle
			(at 32.541718 -24.614886 270)
			(size 0.4318 0.4318)
			(layers "F.Cu" "F.Mask" "F.Paste")
			(net "UPI_CPU0_CPU1_P2P2_DP<22>")
		)
		(pad "F87" smd oval
			(at 34.169604 -24.614886 45)
			(size 0.381 0.4826)
			(drill
				(offset 0 -0.0508)
			)
			(layers "F.Cu" "F.Mask" "F.Paste")
			(net "UPI_CPU0_CPU1_P2P2_DN<20>")
		)
		(pad "F89" smd oval
			(at 35.797236 -24.614886 45)
			(size 0.381 0.4826)
			(drill
				(offset 0 -0.0508)
			)
			(layers "F.Cu" "F.Mask" "F.Paste")
			(net "GND")
		)
		(pad "G3" smd oval
			(at -35.797236 -24.254714 135)
			(size 0.381 0.4826)
			(drill
				(offset 0 -0.0508)
			)
			(layers "F.Cu" "F.Mask" "F.Paste")
			(net "GND")
		)
		(pad "G5" smd oval
			(at -34.169604 -24.254714 135)
			(size 0.381 0.4826)
			(drill
				(offset 0 -0.0508)
			)
			(layers "F.Cu" "F.Mask" "F.Paste")
			(net "NC_XTAL_CPU0_25M_IN")
		)
		(pad "G7" smd circle
			(at -32.541718 -24.254714 270)
			(size 0.4318 0.4318)
			(layers "F.Cu" "F.Mask" "F.Paste")
			(net "GND")
		)
		(pad "G9" smd circle
			(at -30.914086 -24.254714 270)
			(size 0.4318 0.4318)
			(layers "F.Cu" "F.Mask" "F.Paste")
			(net "M_A_CPU0_SB_DQS_DN<8>")
		)
		(pad "G11" smd circle
			(at -29.2862 -24.254714 270)
			(size 0.4318 0.4318)
			(layers "F.Cu" "F.Mask" "F.Paste")
			(net "GND")
		)
		(pad "G13" smd circle
			(at -27.658314 -24.254714 270)
			(size 0.4318 0.4318)
			(layers "F.Cu" "F.Mask" "F.Paste")
			(net "GND")
		)
		(pad "G15" smd circle
			(at -26.030682 -24.254714 270)
			(size 0.4318 0.4318)
			(layers "F.Cu" "F.Mask" "F.Paste")
			(net "M_B_CPU0_SB_DQS_DP<8>")
		)
		(pad "G17" smd circle
			(at -24.402796 -24.254714 270)
			(size 0.4318 0.4318)
			(layers "F.Cu" "F.Mask" "F.Paste")
			(net "GND")
		)
		(pad "G19" smd circle
			(at -22.77491 -24.254714 270)
			(size 0.4318 0.4318)
			(layers "F.Cu" "F.Mask" "F.Paste")
			(net "GND")
		)
		(pad "G21" smd circle
			(at -21.147278 -24.254714 270)
			(size 0.4318 0.4318)
			(layers "F.Cu" "F.Mask" "F.Paste")
			(net "M_A_CPU0_SB_DQS_DN<7>")
		)
		(pad "G23" smd circle
			(at -19.519392 -24.254714 270)
			(size 0.4318 0.4318)
			(layers "F.Cu" "F.Mask" "F.Paste")
			(net "GND")
		)
		(pad "G25" smd circle
			(at -17.89176 -24.254714 270)
			(size 0.4318 0.4318)
			(layers "F.Cu" "F.Mask" "F.Paste")
			(net "GND")
		)
		(pad "G27" smd circle
			(at -16.263874 -24.254714 270)
			(size 0.4318 0.4318)
			(layers "F.Cu" "F.Mask" "F.Paste")
			(net "M_A_CPU0_SB_DQS_DN<6>")
		)
		(pad "G29" smd circle
			(at -14.635988 -24.254714 270)
			(size 0.4318 0.4318)
			(layers "F.Cu" "F.Mask" "F.Paste")
			(net "GND")
		)
		(pad "G31" smd circle
			(at -13.008356 -24.254714 270)
			(size 0.4318 0.4318)
			(layers "F.Cu" "F.Mask" "F.Paste")
			(net "GND")
		)
		(pad "G33" smd circle
			(at -11.380724 -24.254714 270)
			(size 0.4318 0.4318)
			(layers "F.Cu" "F.Mask" "F.Paste")
			(net "M_A_CPU0_SB_DQS_DN<4>")
		)
		(pad "G35" smd circle
			(at -9.752838 -24.254714 270)
			(size 0.4318 0.4318)
			(layers "F.Cu" "F.Mask" "F.Paste")
			(net "GND")
		)
		(pad "G37" smd circle
			(at -8.124952 -24.254714 270)
			(size 0.4318 0.4318)
			(layers "F.Cu" "F.Mask" "F.Paste")
			(net "GND")
		)
		(pad "G39" smd circle
			(at -6.49732 -24.254714 270)
			(size 0.4318 0.4318)
			(layers "F.Cu" "F.Mask" "F.Paste")
			(net "M_A_CPU0_SB_PAR")
		)
		(pad "G41" smd circle
			(at -4.869434 -24.254714 270)
			(size 0.4318 0.4318)
			(layers "F.Cu" "F.Mask" "F.Paste")
			(net "GND")
		)
		(pad "G43" smd circle
			(at -3.241802 -24.254714 270)
			(size 0.4318 0.4318)
			(layers "F.Cu" "F.Mask" "F.Paste")
			(net "GND")
		)
		(pad "G45" smd circle
			(at -1.613916 -24.254714 270)
			(size 0.4318 0.4318)
			(layers "F.Cu" "F.Mask" "F.Paste")
			(net "M_A_CPU0_CLK_DN<1>")
		)
		(pad "G48" smd circle
			(at 2.427732 -24.144986 270)
			(size 0.4318 0.4318)
			(layers "F.Cu" "F.Mask" "F.Paste")
			(net "GND")
		)
		(pad "G50" smd circle
			(at 4.055618 -24.144986 270)
			(size 0.4318 0.4318)
			(layers "F.Cu" "F.Mask" "F.Paste")
			(net "GND")
		)
		(pad "G52" smd circle
			(at 5.68325 -24.144986 270)
			(size 0.4318 0.4318)
			(layers "F.Cu" "F.Mask" "F.Paste")
			(net "M_A_CPU0_SA_CA<1>")
		)
		(pad "G54" smd circle
			(at 7.311136 -24.144986 270)
			(size 0.4318 0.4318)
			(layers "F.Cu" "F.Mask" "F.Paste")
			(net "GND")
		)
		(pad "G56" smd circle
			(at 8.939022 -24.144986 270)
			(size 0.4318 0.4318)
			(layers "F.Cu" "F.Mask" "F.Paste")
			(net "GND")
		)
		(pad "G58" smd circle
			(at 10.566654 -24.144986 270)
			(size 0.4318 0.4318)
			(layers "F.Cu" "F.Mask" "F.Paste")
			(net "M_A_CPU0_SA_DQS_DN<9>")
		)
		(pad "G60" smd circle
			(at 12.19454 -24.144986 270)
			(size 0.4318 0.4318)
			(layers "F.Cu" "F.Mask" "F.Paste")
			(net "GND")
		)
		(pad "G62" smd circle
			(at 13.822426 -24.144986 270)
			(size 0.4318 0.4318)
			(layers "F.Cu" "F.Mask" "F.Paste")
			(net "GND")
		)
		(pad "G64" smd circle
			(at 15.450058 -24.144986 270)
			(size 0.4318 0.4318)
			(layers "F.Cu" "F.Mask" "F.Paste")
			(net "M_A_CPU0_SA_DQS_DN<8>")
		)
		(pad "G66" smd circle
			(at 17.07769 -24.144986 270)
			(size 0.4318 0.4318)
			(layers "F.Cu" "F.Mask" "F.Paste")
			(net "GND")
		)
		(pad "G68" smd circle
			(at 18.705576 -24.144986 270)
			(size 0.4318 0.4318)
			(layers "F.Cu" "F.Mask" "F.Paste")
			(net "GND")
		)
		(pad "G70" smd circle
			(at 20.333462 -24.144986 270)
			(size 0.4318 0.4318)
			(layers "F.Cu" "F.Mask" "F.Paste")
			(net "M_A_CPU0_SA_DQS_DN<7>")
		)
		(pad "G72" smd circle
			(at 21.961094 -24.144986 270)
			(size 0.4318 0.4318)
			(layers "F.Cu" "F.Mask" "F.Paste")
			(net "GND")
		)
		(pad "G74" smd circle
			(at 23.58898 -24.144986 270)
			(size 0.4318 0.4318)
			(layers "F.Cu" "F.Mask" "F.Paste")
			(net "GND")
		)
		(pad "G76" smd circle
			(at 25.216612 -24.144986 270)
			(size 0.4318 0.4318)
			(layers "F.Cu" "F.Mask" "F.Paste")
			(net "M_A_CPU0_SA_DQ<6>")
		)
		(pad "G78" smd circle
			(at 26.844498 -24.144986 270)
			(size 0.4318 0.4318)
			(layers "F.Cu" "F.Mask" "F.Paste")
			(net "M_A_CPU0_SA_DQ<3>")
		)
		(pad "G80" smd circle
			(at 28.472384 -24.144986 270)
			(size 0.4318 0.4318)
			(layers "F.Cu" "F.Mask" "F.Paste")
			(net "UPI_CPU1_CPU0_P2P2_DP<23>")
		)
		(pad "G82" smd circle
			(at 30.100016 -24.144986 270)
			(size 0.4318 0.4318)
			(layers "F.Cu" "F.Mask" "F.Paste")
			(net "UPI_CPU1_CPU0_P2P2_DN<21>")
		)
		(pad "G84" smd circle
			(at 31.727902 -24.144986 270)
			(size 0.4318 0.4318)
			(layers "F.Cu" "F.Mask" "F.Paste")
			(net "GND")
		)
		(pad "G86" smd circle
			(at 33.355534 -24.144986 270)
			(size 0.4318 0.4318)
			(layers "F.Cu" "F.Mask" "F.Paste")
			(net "UPI_CPU0_CPU1_P2P2_DP<19>")
		)
		(pad "G88" smd oval
			(at 34.98342 -24.144986 45)
			(size 0.381 0.4826)
			(drill
				(offset 0 -0.0508)
			)
			(layers "F.Cu" "F.Mask" "F.Paste")
			(net "GND")
		)
		(pad "G90" smd oval
			(at 36.611306 -24.144986 45)
			(size 0.381 0.4826)
			(drill
				(offset 0 -0.0508)
			)
			(layers "F.Cu" "F.Mask" "F.Paste")
			(net "GND")
		)
		(pad "H2" smd oval
			(at -36.611306 -23.784814 135)
			(size 0.381 0.4826)
			(drill
				(offset 0 -0.0508)
			)
			(layers "F.Cu" "F.Mask" "F.Paste")
			(net "GND")
		)
		(pad "H4" smd oval
			(at -34.98342 -23.784814 135)
			(size 0.381 0.4826)
			(drill
				(offset 0 -0.0508)
			)
			(layers "F.Cu" "F.Mask" "F.Paste")
			(net "GND")
		)
		(pad "H6" smd circle
			(at -33.355534 -23.784814 270)
			(size 0.4318 0.4318)
			(layers "F.Cu" "F.Mask" "F.Paste")
			(net "GND")
		)
		(pad "H8" smd circle
			(at -31.727902 -23.784814 270)
			(size 0.4318 0.4318)
			(layers "F.Cu" "F.Mask" "F.Paste")
			(net "GND")
		)
		(pad "H10" smd circle
			(at -30.100016 -23.784814 270)
			(size 0.4318 0.4318)
			(layers "F.Cu" "F.Mask" "F.Paste")
			(net "GND")
		)
		(pad "H12" smd circle
			(at -28.472384 -23.784814 270)
			(size 0.4318 0.4318)
			(layers "F.Cu" "F.Mask" "F.Paste")
			(net "TP_CPU0_A0_DEBUG_EN")
		)
		(pad "H14" smd circle
			(at -26.844498 -23.784814 270)
			(size 0.4318 0.4318)
			(layers "F.Cu" "F.Mask" "F.Paste")
			(net "GND")
		)
		(pad "H16" smd circle
			(at -25.216612 -23.784814 270)
			(size 0.4318 0.4318)
			(layers "F.Cu" "F.Mask" "F.Paste")
			(net "GND")
		)
		(pad "H18" smd circle
			(at -23.58898 -23.784814 270)
			(size 0.4318 0.4318)
			(layers "F.Cu" "F.Mask" "F.Paste")
			(net "M_B_CPU0_SB_DQS_DN<2>")
		)
		(pad "H20" smd circle
			(at -21.961094 -23.784814 270)
			(size 0.4318 0.4318)
			(layers "F.Cu" "F.Mask" "F.Paste")
			(net "GND")
		)
	)
)
